# SCM (Grand Teton) — schematic netlist excerpt (pin names and nets, part order shuffled) for the footprints in the layout excerpt that follows; sources: Cadence DE-HDL packaged netlist, KiCad conversion of 12092022_DA0F0TMDCD0_F0T_Management_Board_D_brd_V3_OCP.brd

C283  Q_CAP  0.01UF 50V 10% EMPTY  pkg C0402  page 41 : A = VCCIO0 ; B = GND
R95  Q_RES  0 5% CHIP  pkg 0402LF  page 28 : A = SMB_DEBUG_AUX_LVC3_USB_SDA ; B = SMB_DEBUG_AUX_LVC3_USB_R3_SDA

(kicad_pcb
	(version 20260206)
	(generator "pcbnew")
	(generator_version "10.0")
	(general
		(thickness 1.6)
		(legacy_teardrops no)
	)
	(paper "A4")
	(title_block
		(title "12092022_DA0F0TMDCD0_F0T_Management_Board_D_brd_V3_OCP.brd")
		(comment 1 "Grand Teton / footprints 1390-1391 of 1440")
	)
	(layers
		(0 "F.Cu" signal "TOP")
		(4 "In1.Cu" signal "GND")
		(6 "In2.Cu" signal "IN1")
		(8 "In3.Cu" signal "GND1")
		(10 "In4.Cu" signal "IN2")
		(12 "In5.Cu" signal "VCC")
		(14 "In6.Cu" signal "VCC1")
		(16 "In7.Cu" signal "IN3")
		(18 "In8.Cu" signal "GND2")
		(20 "In9.Cu" signal "IN4")
		(22 "In10.Cu" signal "GND3")
		(2 "B.Cu" signal "BOTTOM")
		(9 "F.Adhes" user "F.Adhesive")
		(11 "B.Adhes" user "B.Adhesive")
		(13 "F.Paste" user "Package Geometry/Pastemask Top")
		(15 "B.Paste" user "Package Geometry/Pastemask Bottom")
		(5 "F.SilkS" user "Ref Des/Silkscreen Top")
		(7 "B.SilkS" user "Ref Des/Silkscreen Bottom")
		(1 "F.Mask" user "Board Geometry/Soldermask Top")
		(3 "B.Mask" user "Board Geometry/Soldermask Bottom")
		(17 "Dwgs.User" user "User.Drawings")
		(19 "Cmts.User" user "User.Comments")
		(21 "Eco1.User" user "User.Eco1")
		(23 "Eco2.User" user "User.Eco2")
		(25 "Edge.Cuts" user "Board Geometry/Outline")
		(27 "Margin" user)
		(31 "F.CrtYd" user "Package Geometry/Place Bound Top")
		(29 "B.CrtYd" user "Package Geometry/Place Bound Bottom")
		(35 "F.Fab" user "Ref Des/Assembly Top")
		(33 "B.Fab" user "Ref Des/Assembly Bottom")
	)
	(footprint ""
		(layer "B.Cu")
		(at 51.2445 -94.1705 180)
		(property "Reference" "R95"
			(at 0 0 0)
			(layer "B.SilkS")
			(hide yes)
			(effects
				(font
					(size 1.27 1.27)
				)
				(justify mirror)
			)
		)
		(property "Value" ""
			(at 0 0 0)
			(layer "B.Fab")
			(effects
				(font
					(size 1.27 1.27)
				)
				(justify mirror)
			)
		)
		(duplicate_pad_numbers_are_jumpers no)
		(fp_line
			(start 0.7874 0.4064)
			(end 0.7874 -0.4064)
			(stroke
				(width 0.1524)
				(type default)
			)
			(layer "B.SilkS")
		)
		(fp_line
			(start 0.7874 -0.4064)
			(end -0.7874 -0.4064)
			(stroke
				(width 0.1524)
				(type default)
			)
			(layer "B.SilkS")
		)
		(fp_line
			(start -0.7874 0.4064)
			(end 0.7874 0.4064)
			(stroke
				(width 0.1524)
				(type default)
			)
			(layer "B.SilkS")
		)
		(fp_line
			(start -0.7874 -0.4064)
			(end -0.7874 0.4064)
			(stroke
				(width 0.1524)
				(type default)
			)
			(layer "B.SilkS")
		)
		(fp_line
			(start 0.67945 0.3048)
			(end 0.67945 -0.305054)
			(stroke
				(width 0.1)
				(type default)
			)
			(layer "B.Fab")
		)
		(fp_line
			(start 0.67945 -0.305054)
			(end 0.12065 -0.305054)
			(stroke
				(width 0.1)
				(type default)
			)
			(layer "B.Fab")
		)
		(fp_line
			(start 0.12065 0.3048)
			(end 0.67945 0.3048)
			(stroke
				(width 0.1)
				(type default)
			)
			(layer "B.Fab")
		)
		(fp_line
			(start 0.12065 0.2794)
			(end 0.12065 0.3048)
			(stroke
				(width 0.1)
				(type default)
			)
			(layer "B.Fab")
		)
		(fp_line
			(start 0.12065 -0.2794)
			(end -0.12065 -0.2794)
			(stroke
				(width 0.1)
				(type default)
			)
			(layer "B.Fab")
		)
		(fp_line
			(start 0.12065 -0.305054)
			(end 0.12065 -0.2794)
			(stroke
				(width 0.1)
				(type default)
			)
			(layer "B.Fab")
		)
		(fp_line
			(start -0.120396 0.3048)
			(end -0.120396 0.2794)
			(stroke
				(width 0.1)
				(type default)
			)
			(layer "B.Fab")
		)
		(fp_line
			(start -0.120396 0.2794)
			(end 0.12065 0.2794)
			(stroke
				(width 0.1)
				(type default)
			)
			(layer "B.Fab")
		)
		(fp_line
			(start -0.12065 -0.2794)
			(end -0.12065 -0.3048)
			(stroke
				(width 0.1)
				(type default)
			)
			(layer "B.Fab")
		)
		(fp_line
			(start -0.12065 -0.3048)
			(end -0.67945 -0.3048)
			(stroke
				(width 0.1)
				(type default)
			)
			(layer "B.Fab")
		)
		(fp_line
			(start -0.67945 0.3048)
			(end -0.120396 0.3048)
			(stroke
				(width 0.1)
				(type default)
			)
			(layer "B.Fab")
		)
		(fp_line
			(start -0.67945 -0.3048)
			(end -0.67945 0.3048)
			(stroke
				(width 0.1)
				(type default)
			)
			(layer "B.Fab")
		)
		(pad "1" smd circle
			(at 0.40005 0)
			(size 0 0)
			(layers "B.Cu" "B.Mask" "B.Paste")
			(net "SMB_DEBUG_AUX_LVC3_USB_SDA")
		)
		(pad "2" smd circle
			(at -0.40005 0)
			(size 0 0)
			(layers "B.Cu" "B.Mask" "B.Paste")
			(net "SMB_DEBUG_AUX_LVC3_USB_R3_SDA")
		)
	)
	(footprint ""
		(layer "B.Cu")
		(at 18.259298 -89.18702 180)
		(property "Reference" "C283"
			(at 0 0 0)
			(layer "B.SilkS")
			(hide yes)
			(effects
				(font
					(size 1.27 1.27)
				)
				(justify mirror)
			)
		)
		(property "Value" ""
			(at 0 0 0)
			(layer "B.Fab")
			(effects
				(font
					(size 1.27 1.27)
				)
				(justify mirror)
			)
		)
		(duplicate_pad_numbers_are_jumpers no)
		(fp_line
			(start 0.69215 0.2921)
			(end 0.69215 -0.2921)
			(stroke
				(width 0.1524)
				(type default)
			)
			(layer "B.SilkS")
		)
		(fp_line
			(start 0.69215 -0.2921)
			(end -0.69215 -0.2921)
			(stroke
				(width 0.1524)
				(type default)
			)
			(layer "B.SilkS")
		)
		(fp_line
			(start -0.69215 0.2921)
			(end 0.69215 0.2921)
			(stroke
				(width 0.1524)
				(type default)
			)
			(layer "B.SilkS")
		)
		(fp_line
			(start -0.69215 -0.2921)
			(end -0.69215 0.2921)
			(stroke
				(width 0.1524)
				(type default)
			)
			(layer "B.SilkS")
		)
		(fp_line
			(start 0.51435 0.2794)
			(end 0.51435 -0.2794)
			(stroke
				(width 0.1)
				(type default)
			)
			(layer "B.Fab")
		)
		(fp_line
			(start 0.51435 -0.2794)
			(end -0.51435 -0.2794)
			(stroke
				(width 0.1)
				(type default)
			)
			(layer "B.Fab")
		)
		(fp_line
			(start -0.51435 0.2794)
			(end 0.51435 0.2794)
			(stroke
				(width 0.1)
				(type default)
			)
			(layer "B.Fab")
		)
		(fp_line
			(start -0.51435 -0.2794)
			(end -0.51435 0.2794)
			(stroke
				(width 0.1)
				(type default)
			)
			(layer "B.Fab")
		)
		(pad "1" smd circle
			(at 0.40005 0)
			(size 0 0)
			(layers "B.Cu" "B.Mask" "B.Paste")
			(net "VCCIO0")
		)
		(pad "2" smd circle
			(at -0.40005 0)
			(size 0 0)
			(layers "B.Cu" "B.Mask" "B.Paste")
			(net "GND")
		)
		(zone
			(layer "B.Cu")
			(hatch none 0.5)
			(connect_pads
				(clearance 0)
			)
			(min_thickness 0.25)
			(keepout
				(tracks not_allowed)
				(vias allowed)
				(pads allowed)
				(copperpour not_allowed)
				(footprints allowed)
			)
			(placement
				(enabled no)
				(sheetname "")
			)
			(fill
				(thermal_gap 0.5)
				(thermal_bridge_width 0.5)
				(island_removal_mode 0)
			)
			(polygon
				(pts
					(xy 18.068798 -89.27465) (xy 18.160238 -89.332816) (xy 18.359628 -89.332816) (xy 18.449798 -89.27465)
					(xy 18.449798 -89.09939) (xy 18.359628 -89.04097) (xy 18.160238 -89.04097) (xy 18.068798 -89.099136)
				)
			)
		)
	)
)
